FILE_TYPE=LIBRARY_PARTS;
primitive 'FUSE','FUSE_SM','FUSE_SMT','FUSE_THLF';
  pin
    'A'<0>:
      PIN_NUMBER='(1)';
      PINUSE='UNSPEC';
      NO_LOAD_CHECK='BOTH';
      NO_IO_CHECK='BOTH';
      ALLOW_CONNECT='TRUE';
      PIN_GROUP='1';
    'B'<0>:
      PIN_NUMBER='(2)';
      PINUSE='UNSPEC';
      NO_LOAD_CHECK='BOTH';
      NO_IO_CHECK='BOTH';
      ALLOW_CONNECT='TRUE';
      PIN_GROUP='1';
  end_pin;
  body
    PART_NAME='FUSE';
    PHYS_DES_PREFIX='F';
  end_body;
end_primitive;
END.
